# S9S_MB_2U (Grand Teton) — schematic parts with pin connectivity, parts 1610–1610 of 6093; source: Cadence DE-HDL packaged netlist (pstxprt.dat, pstxnet.dat, pstchip.dat)

J17  SCONN288_ADR50017P130CC  SCONN288_ADR50017-P130CC IO  pkg DDR288S_1-1VXB  page 98
  1  VIN_BULK0  POWER  = P12V_S3_AUX_CPU1_NVDIMM
  2  RFU0  TRI  = TP_CHA_CPU1_DIMM1_FRU_0
  3  VIN_MGMT  POWER  = P3V3_AUX
  4  HSCL  IN  = I3C_SPD_DDRABCD_CPU1_LVC1_SCL_R
  5  HSDA  BI  = I3C_SPD_DDRABCD_CPU1_LVC1_SDA
  6  VSS0  POWER  = GND
  7  DQ0_A  BI  = M_A_CPU1_SA_DQ<0>
  8  VSS1  POWER  = GND
  9  DQ1_A  BI  = M_A_CPU1_SA_DQ<1>
  10  VSS2  POWER  = GND
  11  DQS0_A_T  BI  = M_A_CPU1_SA_DQS_DP<0>
  12  DQS0_A_C  BI  = M_A_CPU1_SA_DQS_DN<0>
  13  VSS3  POWER  = GND
  14  DQ4_A  BI  = M_A_CPU1_SA_DQ<4>
  15  VSS4  POWER  = GND
  16  DQ5_A  BI  = M_A_CPU1_SA_DQ<5>
  17  VSS5  POWER  = GND
  18  DQ8_A  BI  = M_A_CPU1_SA_DQ<8>
  19  VSS6  POWER  = GND
  20  DQ9_A  BI  = M_A_CPU1_SA_DQ<9>
  21  VSS7  POWER  = GND
  22  DQS1_A_T  BI  = M_A_CPU1_SA_DQS_DP<1>
  23  DQS1_A_C  BI  = M_A_CPU1_SA_DQS_DN<1>
  24  VSS8  POWER  = GND
  25  DQ12_A  BI  = M_A_CPU1_SA_DQ<12>
  26  VSS9  POWER  = GND
  27  DQ13_A  BI  = M_A_CPU1_SA_DQ<13>
  28  VSS10  POWER  = GND
  29  DQ16_A  BI  = M_A_CPU1_SA_DQ<16>
  30  VSS11  POWER  = GND
  31  DQ17_A  BI  = M_A_CPU1_SA_DQ<17>
  32  VSS12  POWER  = GND
  33  DQS2_A_T  BI  = M_A_CPU1_SA_DQS_DP<2>
  34  DQS2_A_C  BI  = M_A_CPU1_SA_DQS_DN<2>
  35  VSS13  POWER  = GND
  36  DQ20_A  BI  = M_A_CPU1_SA_DQ<20>
  37  VSS14  POWER  = GND
  38  DQ21_A  BI  = M_A_CPU1_SA_DQ<21>
  39  VSS15  POWER  = GND
  40  DQ24_A  BI  = M_A_CPU1_SA_DQ<24>
  41  VSS16  POWER  = GND
  42  DQ25_A  BI  = M_A_CPU1_SA_DQ<25>
  43  VSS17  POWER  = GND
  44  DQS3_A_T  BI  = M_A_CPU1_SA_DQS_DP<3>
  45  DQS3_A_C  BI  = M_A_CPU1_SA_DQS_DN<3>
  46  VSS18  POWER  = GND
  47  DQ28_A  BI  = M_A_CPU1_SA_DQ<28>
  48  VSS19  POWER  = GND
  49  DQ29_A  BI  = M_A_CPU1_SA_DQ<29>
  50  VSS20  POWER  = GND
  51  CB0_A  BI  = M_A_CPU1_SA_CB<0>
  52  VSS21  POWER  = GND
  53  CB1_A  BI  = M_A_CPU1_SA_CB<1>
  54  VSS22  POWER  = GND
  55  DQS4_A_T  BI  = M_A_CPU1_SA_DQS_DP<4>
  56  DQS4_A_C  BI  = M_A_CPU1_SA_DQS_DN<4>
  57  VSS23  POWER  = GND
  58  CB4_A  BI  = M_A_CPU1_SA_CB<4>
  59  VSS24  POWER  = GND
  60  CB5_A  BI  = M_A_CPU1_SA_CB<5>
  61  VSS25  POWER  = GND
  62  ALERT_N  OUT  = M_A_CPU1_ALERT_N
  63  VSS26  POWER  = GND
  64  CS0_A_N  IN  = M_A_CPU1_SA_CS_N<0>
  65  VSS27  POWER  = GND
  66  CA0_A  IN  = M_A_CPU1_SA_CA<0>
  67  VSS28  POWER  = GND
  68  CA2_A  IN  = M_A_CPU1_SA_CA<2>
  69  VSS29  POWER  = GND
  70  CA4_A  IN  = M_A_CPU1_SA_CA<4>
  71  VSS30  POWER  = GND
  72  CA6_A  IN  = M_A_CPU1_SA_CA<6>
  73  VSS31  POWER  = GND
  74  PAR_A  IN  = M_A_CPU1_SA_PAR
  75  VSS32  POWER  = GND
  76  CA0_B  IN  = M_A_CPU1_SB_CA<0>
  77  VSS33  POWER  = GND
  78  CA2_B  IN  = M_A_CPU1_SB_CA<2>
  79  VSS34  POWER  = GND
  80  CA4_B  IN  = M_A_CPU1_SB_CA<4>
  81  VSS35  POWER  = GND
  82  CA6_B  IN  = M_A_CPU1_SB_CA<6>
  83  VSS36  POWER  = GND
  84  CS0_B_N  IN  = M_A_CPU1_SB_CS_N<0>
  85  VSS37  POWER  = GND
  86  \lbd||rsp_a_n\  OUT  = M_A_CPU1_SA_RSP<0>
  87  \lbs||rsp_b_n\  OUT  = M_A_CPU1_SB_RSP<0>
  88  VSS38  POWER  = GND
  89  CB4_B  BI  = M_A_CPU1_SB_CB<4>
  90  VSS39  POWER  = GND
  91  CB5_B  BI  = M_A_CPU1_SB_CB<5>
  92  VSS40  POWER  = GND
  93  \dqs9_b_t||tdqs9_b_t||dbi4_b_n\  BI  = M_A_CPU1_SB_DQS_DP<9>
  94  \dqs9_b_c||tdqs9_b_c\  BI  = M_A_CPU1_SB_DQS_DN<9>
  95  VSS41  POWER  = GND
  96  CB0_B  BI  = M_A_CPU1_SB_CB<0>
  97  VSS42  POWER  = GND
  98  CB1_B  BI  = M_A_CPU1_SB_CB<1>
  99  VSS43  POWER  = GND
  100  DQ0_B  BI  = M_A_CPU1_SB_DQ<0>
  101  VSS44  POWER  = GND
  102  DQ1_B  BI  = M_A_CPU1_SB_DQ<1>
  103  VSS45  POWER  = GND
  104  DQS0_B_T  BI  = M_A_CPU1_SB_DQS_DP<0>
  105  DQS0_B_C  BI  = M_A_CPU1_SB_DQS_DN<0>
  106  VSS46  POWER  = GND
  107  DQ4_B  BI  = M_A_CPU1_SB_DQ<4>
  108  VSS47  POWER  = GND
  109  DQ5_B  BI  = M_A_CPU1_SB_DQ<5>
  110  VSS48  POWER  = GND
  111  DQ8_B  BI  = M_A_CPU1_SB_DQ<8>
  112  VSS49  POWER  = GND
  113  DQ9_B  BI  = M_A_CPU1_SB_DQ<9>
  114  VSS50  POWER  = GND
  115  DQS1_B_T  BI  = M_A_CPU1_SB_DQS_DP<1>
  116  DQS1_B_C  BI  = M_A_CPU1_SB_DQS_DN<1>
  117  VSS51  POWER  = GND
  118  DQ12_B  BI  = M_A_CPU1_SB_DQ<12>
  119  VSS52  POWER  = GND
  120  DQ13_B  BI  = M_A_CPU1_SB_DQ<13>
  121  VSS53  POWER  = GND
  122  DQ16_B  BI  = M_A_CPU1_SB_DQ<16>
  123  VSS54  POWER  = GND
  124  DQ17_B  BI  = M_A_CPU1_SB_DQ<17>
  125  VSS55  POWER  = GND
  126  DQS2_B_T  BI  = M_A_CPU1_SB_DQS_DP<2>
  127  DQS2_B_C  BI  = M_A_CPU1_SB_DQS_DN<2>
  128  VSS56  POWER  = GND
  129  DQ20_B  BI  = M_A_CPU1_SB_DQ<20>
  130  VSS57  POWER  = GND
  131  DQ21_B  BI  = M_A_CPU1_SB_DQ<21>
  132  VSS58  POWER  = GND
  133  DQ24_B  BI  = M_A_CPU1_SB_DQ<24>
  134  VSS59  POWER  = GND
  135  DQ25_B  BI  = M_A_CPU1_SB_DQ<25>
  136  VSS60  POWER  = GND
  137  DQS3_B_T  BI  = M_A_CPU1_SB_DQS_DP<3>
  138  DQS3_B_C  BI  = M_A_CPU1_SB_DQS_DN<3>
  139  VSS61  POWER  = GND
  140  DQ28_B  BI  = M_A_CPU1_SB_DQ<28>
  141  VSS62  POWER  = GND
  142  DQ29_B  BI  = M_A_CPU1_SB_DQ<29>
  143  VSS63  POWER  = GND
  144  RFU1  TRI  = TP_CHA_CPU1_DIMM1_FRU_1
  145  VIN_BULK1  POWER  = P12V_S3_AUX_CPU1_NVDIMM
  146  VIN_BULK2  POWER  = P12V_S3_AUX_CPU1_NVDIMM
  147  \pwr_good||fail_n\  BI  = PWRGD_CHA_CPU1_DIMM1
  148  HSA  IN  = PD_CHA_CPU1_DIMM1_SAA
  149  RFU2  TRI  = TP_CHA_CPU1_DIMM1_FRU_2
  150  RFU3  TRI  = TP_CHA_CPU1_DIMM1_FRU_3
  151  VSS64  POWER  = GND
  152  DQ2_A  BI  = M_A_CPU1_SA_DQ<2>
  153  VSS65  POWER  = GND
  154  DQ3_A  BI  = M_A_CPU1_SA_DQ<3>
  155  VSS66  POWER  = GND
  156  \dqs5_a_c||tdqs5_a_c||dqs5_a_t||tdqs5_a_t\  BI  = M_A_CPU1_SA_DQS_DN<5>
  157  \dqs5_a_t||tdqs5_a_t\  BI  = M_A_CPU1_SA_DQS_DP<5>
  158  VSS67  POWER  = GND
  159  DQ6_A  BI  = M_A_CPU1_SA_DQ<6>
  160  VSS68  POWER  = GND
  161  DQ7_A  BI  = M_A_CPU1_SA_DQ<7>
  162  VSS69  POWER  = GND
  163  DQ10_A  BI  = M_A_CPU1_SA_DQ<10>
  164  VSS70  POWER  = GND
  165  DQ11_A  BI  = M_A_CPU1_SA_DQ<11>
  166  VSS71  POWER  = GND
  167  \dqs6_a_c||tdqs6_a_c||dqs6_a_t||tdqs6_a_t\  BI  = M_A_CPU1_SA_DQS_DN<6>
  168  \dqs6_a_t||tdqs6_a_t\  BI  = M_A_CPU1_SA_DQS_DP<6>
  169  VSS72  POWER  = GND
  170  DQ14_A  BI  = M_A_CPU1_SA_DQ<14>
  171  VSS73  POWER  = GND
  172  DQ15_A  BI  = M_A_CPU1_SA_DQ<15>
  173  VSS74  POWER  = GND
  174  DQ18_A  BI  = M_A_CPU1_SA_DQ<18>
  175  VSS75  POWER  = GND
  176  DQ19_A  BI  = M_A_CPU1_SA_DQ<19>
  177  VSS76  POWER  = GND
  178  \dqs7_a_c||tdqs7_a_c\  BI  = M_A_CPU1_SA_DQS_DN<7>
  179  \dqs7_a_t||tdqs7_a_t\  BI  = M_A_CPU1_SA_DQS_DP<7>
  180  VSS77  POWER  = GND
  181  DQ22_A  BI  = M_A_CPU1_SA_DQ<22>
  182  VSS78  POWER  = GND
  183  DQ23_A  BI  = M_A_CPU1_SA_DQ<23>
  184  VSS79  POWER  = GND
  185  DQ26_A  BI  = M_A_CPU1_SA_DQ<26>
  186  VSS80  POWER  = GND
  187  DQ27_A  BI  = M_A_CPU1_SA_DQ<27>
  188  VSS81  POWER  = GND
  189  \dqs8_a_c||tdqs8_a_c\  BI  = M_A_CPU1_SA_DQS_DN<8>
  190  \dqs8_a_t||tdqs8_a_t\  BI  = M_A_CPU1_SA_DQS_DP<8>
  191  VSS82  POWER  = GND
  192  DQ30_A  BI  = M_A_CPU1_SA_DQ<30>
  193  VSS83  POWER  = GND
  194  DQ31_A  BI  = M_A_CPU1_SA_DQ<31>
  195  VSS84  POWER  = GND
  196  CB2_A  BI  = M_A_CPU1_SA_CB<2>
  197  VSS85  POWER  = GND
  198  CB3_A  BI  = M_A_CPU1_SA_CB<3>
  199  VSS86  POWER  = GND
  200  \dqs9_a_c||tdqs9_a_c\  BI  = M_A_CPU1_SA_DQS_DN<9>
  201  \dqs9_a_t||tdqs9_a_t\  BI  = M_A_CPU1_SA_DQS_DP<9>
  202  VSS87  POWER  = GND
  203  CB6_A  BI  = M_A_CPU1_SA_CB<6>
  204  VSS88  POWER  = GND
  205  CB7_A  BI  = M_A_CPU1_SA_CB<7>
  206  VSS89  POWER  = GND
  207  RESET_N  IN  = RST_M_AB_CPU1_FPGA_N
  208  VSS90  POWER  = GND
  209  CS1_A_N  IN  = M_A_CPU1_SA_CS_N<1>
  210  VSS91  POWER  = GND
  211  CA1_A  IN  = M_A_CPU1_SA_CA<1>
  212  VSS92  POWER  = GND
  213  CA3_A  IN  = M_A_CPU1_SA_CA<3>
  214  VSS93  POWER  = GND
  215  CA5_A  IN  = M_A_CPU1_SA_CA<5>
  216  VSS94  POWER  = GND
  217  CK_T  IN  = M_A_CPU1_CLK_DP<0>
  218  CK_C  IN  = M_A_CPU1_CLK_DN<0>
  219  VSS95  POWER  = GND
  220  RFU4  TRI  = TP_CHA_CPU1_DIMM1_FRU_4
  221  CA1_B  IN  = M_A_CPU1_SB_CA<1>
  222  VSS96  POWER  = GND
  223  CA3_B  IN  = M_A_CPU1_SB_CA<3>
  224  VSS97  POWER  = GND
  225  CA5_B  IN  = M_A_CPU1_SB_CA<5>
  226  VSS98  POWER  = GND
  227  PAR_B  IN  = M_A_CPU1_SB_PAR
  228  VSS99  POWER  = GND
  229  CS1_B_N  IN  = M_A_CPU1_SB_CS_N<1>
  230  VSS100  POWER  = GND
  231  RFU5  TRI  = TP_CHA_CPU1_DIMM1_FRU_5
  232  RFU6  TRI  = TP_CHA_CPU1_DIMM1_FRU_6
  233  VSS101  POWER  = GND
  234  CB6_B  BI  = M_A_CPU1_SB_CB<6>
  235  VSS102  POWER  = GND
  236  CB7_B  BI  = M_A_CPU1_SB_CB<7>
  237  VSS103  POWER  = GND
  238  DQS4_B_C  BI  = M_A_CPU1_SB_DQS_DN<4>
  239  DQS4_B_T  BI  = M_A_CPU1_SB_DQS_DP<4>
  240  VSS104  POWER  = GND
  241  CB2_B  BI  = M_A_CPU1_SB_CB<2>
  242  VSS105  POWER  = GND
  243  CB3_B  BI  = M_A_CPU1_SB_CB<3>
  244  VSS106  POWER  = GND
  245  DQ2_B  BI  = M_A_CPU1_SB_DQ<2>
  246  VSS107  POWER  = GND
  247  DQ3_B  BI  = M_A_CPU1_SB_DQ<3>
  248  VSS108  POWER  = GND
  249  \dqs5_b_c||tdqs5_b_c\  BI  = M_A_CPU1_SB_DQS_DN<5>
  250  \dqs5_b_t||tdqs5_b_t\  BI  = M_A_CPU1_SB_DQS_DP<5>
  251  VSS109  POWER  = GND
  252  DQ6_B  BI  = M_A_CPU1_SB_DQ<6>
  253  VSS110  POWER  = GND
  254  DQ7_B  BI  = M_A_CPU1_SB_DQ<7>
  255  VSS111  POWER  = GND
  256  DQ10_B  BI  = M_A_CPU1_SB_DQ<10>
  257  VSS112  POWER  = GND
  258  DQ11_B  BI  = M_A_CPU1_SB_DQ<11>
  259  VSS113  POWER  = GND
  260  \dqs6_b_c||tdqs6_b_c\  BI  = M_A_CPU1_SB_DQS_DN<6>
  261  \dqs6_b_t||tdqs6_b_t\  BI  = M_A_CPU1_SB_DQS_DP<6>
  262  VSS114  POWER  = GND
  263  DQ14_B  BI  = M_A_CPU1_SB_DQ<14>
  264  VSS115  POWER  = GND
  265  DQ15_B  BI  = M_A_CPU1_SB_DQ<15>
  266  VSS116  POWER  = GND
  267  DQ18_B  BI  = M_A_CPU1_SB_DQ<18>
  268  VSS117  POWER  = GND
  269  DQ19_B  BI  = M_A_CPU1_SB_DQ<19>
  270  VSS118  POWER  = GND
  271  \dqs7_b_c||tdqs7_b_c\  BI  = M_A_CPU1_SB_DQS_DN<7>
  272  \dqs7_b_t||tdqs7_b_t\  BI  = M_A_CPU1_SB_DQS_DP<7>
  273  VSS119  POWER  = GND
  274  DQ22_B  BI  = M_A_CPU1_SB_DQ<22>
  275  VSS120  POWER  = GND
  276  DQ23_B  BI  = M_A_CPU1_SB_DQ<23>
  277  VSS121  POWER  = GND
  278  DQ26_B  BI  = M_A_CPU1_SB_DQ<26>
  279  VSS122  POWER  = GND
  280  DQ27_B  BI  = M_A_CPU1_SB_DQ<27>
  281  VSS123  POWER  = GND
  282  \dqs8_b_c||tdqs8_b_c\  BI  = M_A_CPU1_SB_DQS_DN<8>
  283  \dqs8_b_t||tdqs8_b_t\  BI  = M_A_CPU1_SB_DQS_DP<8>
  284  VSS124  POWER  = GND
  285  DQ30_B  BI  = M_A_CPU1_SB_DQ<30>
  286  VSS125  POWER  = GND
  287  DQ31_B  BI  = M_A_CPU1_SB_DQ<31>
  288  VSS126  POWER  = GND
  G1  G1  POWER  = GND
  G2  G2  POWER  = GND
  G3  G3  POWER  = GND
